(kicad_pcb
	(version 20260206)
	(generator "pcbnew")
	(generator_version "10.0")
	(general
		(thickness 1.6)
		(legacy_teardrops no)
	)
	(paper "A4")
	(title_block
		(title "Wiwynn_Tioga_Pass_MB.brd")
		(comment 1 "Tioga Pass / footprints 242-248 of 4770")
	)
	(layers
		(0 "F.Cu" signal "TOP")
		(4 "In1.Cu" signal "L2GND")
		(6 "In2.Cu" signal "L3")
		(8 "In3.Cu" signal "L4GND")
		(10 "In4.Cu" signal "L5")
		(12 "In5.Cu" signal "L6GND")
		(14 "In6.Cu" signal "L7VCC")
		(16 "In7.Cu" signal "L8VCC")
		(18 "In8.Cu" signal "L9GND")
		(20 "In9.Cu" signal "L10")
		(22 "In10.Cu" signal "L11GND")
		(24 "In11.Cu" signal "L12")
		(26 "In12.Cu" signal "L13GND")
		(2 "B.Cu" signal "BOTTOM")
		(9 "F.Adhes" user "F.Adhesive")
		(11 "B.Adhes" user "B.Adhesive")
		(13 "F.Paste" user "Package Geometry/Pastemask Top")
		(15 "B.Paste" user "Package Geometry/Pastemask Bottom")
		(5 "F.SilkS" user "Ref Des/Silkscreen Top")
		(7 "B.SilkS" user "Ref Des/Silkscreen Bottom")
		(1 "F.Mask" user "Board Geometry/Soldermask Top")
		(3 "B.Mask" user "Board Geometry/Soldermask Bottom")
		(17 "Dwgs.User" user "User.Drawings")
		(19 "Cmts.User" user "User.Comments")
		(21 "Eco1.User" user "User.Eco1")
		(23 "Eco2.User" user "User.Eco2")
		(25 "Edge.Cuts" user "Board Geometry/Outline")
		(27 "Margin" user)
		(31 "F.CrtYd" user "Package Geometry/Place Bound Top")
		(29 "B.CrtYd" user "Package Geometry/Place Bound Bottom")
		(35 "F.Fab" user "Ref Des/Assembly Top")
		(33 "B.Fab" user "Ref Des/Assembly Bottom")
	)
	(footprint ""
		(layer "F.Cu")
		(at 383.14757 -78.902814 90)
		(property "Reference" "R7D28"
			(at 0 0 90)
			(layer "F.SilkS")
			(hide yes)
			(effects
				(font
					(size 1.27 1.27)
				)
			)
		)
		(property "Value" ""
			(at 0 0 90)
			(layer "F.Fab")
			(effects
				(font
					(size 1.27 1.27)
				)
			)
		)
		(duplicate_pad_numbers_are_jumpers no)
		(fp_poly
			(pts
				(xy -0.2794 -0.1016) (xy 0.2794 -0.1016) (xy 0.2794 0.9906) (xy -0.2794 0.9906)
			)
			(stroke
				(width 0)
				(type default)
			)
			(fill no)
			(layer "F.CrtYd")
		)
		(fp_line
			(start 0.2794 -0.1016)
			(end -0.2794 -0.1016)
			(stroke
				(width 0.1)
				(type default)
			)
			(layer "F.Fab")
		)
		(fp_line
			(start -0.2794 -0.1016)
			(end -0.2794 0.9906)
			(stroke
				(width 0.1)
				(type default)
			)
			(layer "F.Fab")
		)
		(fp_line
			(start 0.2794 0.9906)
			(end 0.2794 -0.1016)
			(stroke
				(width 0.1)
				(type default)
			)
			(layer "F.Fab")
		)
		(fp_line
			(start -0.2794 0.9906)
			(end 0.2794 0.9906)
			(stroke
				(width 0.1)
				(type default)
			)
			(layer "F.Fab")
		)
		(pad "1" smd rect
			(at 0 0 90)
			(size 0.508 0.508)
			(layers "F.Cu" "F.Mask" "F.Paste")
			(net "H_CPU1_MSMI_G_N")
		)
		(pad "2" smd rect
			(at 0 0.889 90)
			(size 0.508 0.508)
			(layers "F.Cu" "F.Mask" "F.Paste")
			(net "H_CPU_MSMI_G_N")
		)
		(zone
			(layer "F.Cu")
			(hatch none 0.5)
			(connect_pads
				(clearance 0)
			)
			(min_thickness 0.25)
			(keepout
				(tracks allowed)
				(vias not_allowed)
				(pads allowed)
				(copperpour not_allowed)
				(footprints allowed)
			)
			(placement
				(enabled no)
				(sheetname "")
			)
			(fill
				(thermal_gap 0.5)
				(thermal_bridge_width 0.5)
				(island_removal_mode 0)
			)
			(polygon
				(pts
					(xy 383.40157 -78.648814) (xy 383.40157 -79.156814) (xy 383.78257 -79.156814) (xy 383.78257 -78.648814)
				)
			)
		)
		(zone
			(layer "F.Cu")
			(hatch none 0.5)
			(connect_pads
				(clearance 0)
			)
			(min_thickness 0.25)
			(keepout
				(tracks not_allowed)
				(vias allowed)
				(pads allowed)
				(copperpour not_allowed)
				(footprints allowed)
			)
			(placement
				(enabled no)
				(sheetname "")
			)
			(fill
				(thermal_gap 0.5)
				(thermal_bridge_width 0.5)
				(island_removal_mode 0)
			)
			(polygon
				(pts
					(xy 383.78257 -78.648814) (xy 383.78257 -79.156814) (xy 383.40157 -79.156814) (xy 383.40157 -78.648814)
				)
			)
		)
	)
	(footprint ""
		(layer "F.Cu")
		(at 438.912 -20.828)
		(property "Reference" "CR10W1"
			(at 1.06934 -0.39116 270)
			(unlocked yes)
			(layer "F.SilkS")
			(effects
				(font
					(size 0.4064 0.254)
					(thickness 0.1524)
				)
				(justify left)
			)
		)
		(property "Value" ""
			(at 0 0 0)
			(layer "F.Fab")
			(effects
				(font
					(size 1.27 1.27)
				)
			)
		)
		(duplicate_pad_numbers_are_jumpers no)
		(fp_line
			(start -1.3843 0.038862)
			(end -0.903478 -0.794004)
			(stroke
				(width 0.1524)
				(type default)
			)
			(layer "F.SilkS")
		)
		(fp_line
			(start -0.903478 -1.917446)
			(end -0.903478 -0.794004)
			(stroke
				(width 0.1524)
				(type default)
			)
			(layer "F.SilkS")
		)
		(fp_line
			(start -0.903478 -0.794004)
			(end -0.422656 0.038862)
			(stroke
				(width 0.1524)
				(type default)
			)
			(layer "F.SilkS")
		)
		(fp_line
			(start -0.903478 0.038862)
			(end -1.3843 0.038862)
			(stroke
				(width 0.1524)
				(type default)
			)
			(layer "F.SilkS")
		)
		(fp_line
			(start -0.903478 0.950468)
			(end -0.903478 0.038862)
			(stroke
				(width 0.1524)
				(type default)
			)
			(layer "F.SilkS")
		)
		(fp_line
			(start -0.422656 -0.794004)
			(end -1.3843 -0.794004)
			(stroke
				(width 0.1524)
				(type default)
			)
			(layer "F.SilkS")
		)
		(fp_line
			(start -0.422656 0.038862)
			(end -0.903478 0.038862)
			(stroke
				(width 0.1524)
				(type default)
			)
			(layer "F.SilkS")
		)
		(fp_poly
			(pts
				(xy -0.67437 0.24384) (xy -0.67437 2.04216) (xy 0.67437 2.04216) (xy 0.67437 0.24384)
			)
			(stroke
				(width 0)
				(type default)
			)
			(fill no)
			(layer "F.CrtYd")
		)
		(fp_line
			(start -1.3843 0.038862)
			(end -0.903478 -0.794004)
			(stroke
				(width 0.1)
				(type default)
			)
			(layer "F.Fab")
		)
		(fp_line
			(start -0.903478 -0.794004)
			(end -0.903478 -1.917446)
			(stroke
				(width 0.1)
				(type default)
			)
			(layer "F.Fab")
		)
		(fp_line
			(start -0.903478 -0.794004)
			(end -0.422656 0.038862)
			(stroke
				(width 0.1)
				(type default)
			)
			(layer "F.Fab")
		)
		(fp_line
			(start -0.903478 0.038862)
			(end -0.903478 0.950468)
			(stroke
				(width 0.1)
				(type default)
			)
			(layer "F.Fab")
		)
		(fp_line
			(start -0.67437 0.24384)
			(end -0.67437 2.04216)
			(stroke
				(width 0.1)
				(type default)
			)
			(layer "F.Fab")
		)
		(fp_line
			(start -0.67437 2.04216)
			(end 0.67437 2.04216)
			(stroke
				(width 0.1)
				(type default)
			)
			(layer "F.Fab")
		)
		(fp_line
			(start -0.422656 -0.794004)
			(end -1.3843 -0.794004)
			(stroke
				(width 0.1)
				(type default)
			)
			(layer "F.Fab")
		)
		(fp_line
			(start -0.422656 0.038862)
			(end -1.3843 0.038862)
			(stroke
				(width 0.1)
				(type default)
			)
			(layer "F.Fab")
		)
		(fp_line
			(start 0.67437 0.24384)
			(end -0.67437 0.24384)
			(stroke
				(width 0.1)
				(type default)
			)
			(layer "F.Fab")
		)
		(fp_line
			(start 0.67437 2.04216)
			(end 0.67437 0.24384)
			(stroke
				(width 0.1)
				(type default)
			)
			(layer "F.Fab")
		)
		(pad "1" smd rect
			(at 0 0)
			(size 0.4064 1.016)
			(layers "F.Cu" "F.Mask" "F.Paste")
			(net "PUMP_TACH_D")
		)
		(pad "2" smd rect
			(at 0 2.286)
			(size 0.4064 1.016)
			(layers "F.Cu" "F.Mask" "F.Paste")
			(net "PUMP_TACH_R")
		)
	)
	(footprint ""
		(layer "F.Cu")
		(at 243.735606 -26.591006 -45)
		(property "Reference" "C5F1"
			(at 0 0 315)
			(layer "F.SilkS")
			(hide yes)
			(effects
				(font
					(size 1.27 1.27)
				)
			)
		)
		(property "Value" ""
			(at 0 0 315)
			(layer "F.Fab")
			(effects
				(font
					(size 1.27 1.27)
				)
			)
		)
		(duplicate_pad_numbers_are_jumpers no)
		(fp_poly
			(pts
				(xy -0.500021 -0.201359) (xy 0.500231 -0.201359) (xy 0.500231 1.598486) (xy -0.500021 1.598486)
			)
			(stroke
				(width 0)
				(type default)
			)
			(fill no)
			(layer "F.CrtYd")
		)
		(fp_line
			(start -0.500021 1.598486)
			(end -0.5002 -0.201337)
			(stroke
				(width 0.1)
				(type default)
			)
			(layer "F.Fab")
		)
		(fp_line
			(start 0.500021 1.598486)
			(end -0.500021 1.598486)
			(stroke
				(width 0.1)
				(type default)
			)
			(layer "F.Fab")
		)
		(fp_line
			(start -0.5002 -0.201337)
			(end 0.5002 -0.201337)
			(stroke
				(width 0.1)
				(type default)
			)
			(layer "F.Fab")
		)
		(fp_line
			(start 0.5002 -0.201337)
			(end 0.500021 1.598486)
			(stroke
				(width 0.1)
				(type default)
			)
			(layer "F.Fab")
		)
		(pad "1" smd rect
			(at 0 0 225)
			(size 0.889 0.9906)
			(layers "F.Cu" "F.Mask" "F.Paste")
			(net "PVDDQ_ABC")
		)
		(pad "2" smd rect
			(at 0 1.397 225)
			(size 0.889 0.9906)
			(layers "F.Cu" "F.Mask" "F.Paste")
			(net "GND")
		)
		(zone
			(layer "F.Cu")
			(hatch none 0.5)
			(connect_pads
				(clearance 0)
			)
			(min_thickness 0.25)
			(keepout
				(tracks not_allowed)
				(vias allowed)
				(pads allowed)
				(copperpour not_allowed)
				(footprints allowed)
			)
			(placement
				(enabled no)
				(sheetname "")
			)
			(fill
				(thermal_gap 0.5)
				(thermal_bridge_width 0.5)
				(island_removal_mode 0)
			)
			(polygon
				(pts
					(xy 242.711732 -26.267664) (xy 243.412192 -25.567204) (xy 243.771402 -25.926414) (xy 243.070942 -26.626874)
				)
			)
		)
		(zone
			(layer "F.Cu")
			(hatch none 0.5)
			(connect_pads
				(clearance 0)
			)
			(min_thickness 0.25)
			(keepout
				(tracks allowed)
				(vias not_allowed)
				(pads allowed)
				(copperpour not_allowed)
				(footprints allowed)
			)
			(placement
				(enabled no)
				(sheetname "")
			)
			(fill
				(thermal_gap 0.5)
				(thermal_bridge_width 0.5)
				(island_removal_mode 0)
			)
			(polygon
				(pts
					(xy 242.711732 -26.267664) (xy 243.412192 -25.567204) (xy 243.771402 -25.926414) (xy 243.070942 -26.626874)
				)
			)
		)
	)
	(footprint ""
		(layer "F.Cu")
		(at 94.343728 -13.004292 90)
		(property "Reference" "C2G7"
			(at 0 0 90)
			(layer "F.SilkS")
			(hide yes)
			(effects
				(font
					(size 1.27 1.27)
				)
			)
		)
		(property "Value" ""
			(at 0 0 90)
			(layer "F.Fab")
			(effects
				(font
					(size 1.27 1.27)
				)
			)
		)
		(duplicate_pad_numbers_are_jumpers no)
		(fp_poly
			(pts
				(xy -0.7239 -0.2159) (xy 0.7239 -0.2159) (xy 0.7239 1.9939) (xy -0.7239 1.9939)
			)
			(stroke
				(width 0)
				(type default)
			)
			(fill no)
			(layer "F.CrtYd")
		)
		(fp_line
			(start 0.7239 -0.2159)
			(end -0.7239 -0.2159)
			(stroke
				(width 0.1)
				(type default)
			)
			(layer "F.Fab")
		)
		(fp_line
			(start -0.7239 -0.2159)
			(end -0.7239 1.9939)
			(stroke
				(width 0.1)
				(type default)
			)
			(layer "F.Fab")
		)
		(fp_line
			(start 0.7239 1.9939)
			(end 0.7239 -0.2159)
			(stroke
				(width 0.1)
				(type default)
			)
			(layer "F.Fab")
		)
		(fp_line
			(start -0.7239 1.9939)
			(end 0.7239 1.9939)
			(stroke
				(width 0.1)
				(type default)
			)
			(layer "F.Fab")
		)
		(pad "1" smd rect
			(at 0 0 90)
			(size 1.27 1.016)
			(layers "F.Cu" "F.Mask" "F.Paste")
			(net "PVDDQ_GHJ")
		)
		(pad "2" smd rect
			(at 0 1.778 90)
			(size 1.27 1.016)
			(layers "F.Cu" "F.Mask" "F.Paste")
			(net "GND")
		)
		(zone
			(layer "F.Cu")
			(hatch none 0.5)
			(connect_pads
				(clearance 0)
			)
			(min_thickness 0.25)
			(keepout
				(tracks not_allowed)
				(vias allowed)
				(pads allowed)
				(copperpour not_allowed)
				(footprints allowed)
			)
			(placement
				(enabled no)
				(sheetname "")
			)
			(fill
				(thermal_gap 0.5)
				(thermal_bridge_width 0.5)
				(island_removal_mode 0)
			)
			(polygon
				(pts
					(xy 94.851728 -12.369292) (xy 94.851728 -13.639292) (xy 95.613728 -13.639292) (xy 95.613728 -12.369292)
				)
			)
		)
	)
	(footprint ""
		(layer "F.Cu")
		(at 490.2581 -45.9994 90)
		(property "Reference" "R9E9"
			(at 0 0 90)
			(layer "F.SilkS")
			(hide yes)
			(effects
				(font
					(size 1.27 1.27)
				)
			)
		)
		(property "Value" ""
			(at 0 0 90)
			(layer "F.Fab")
			(effects
				(font
					(size 1.27 1.27)
				)
			)
		)
		(duplicate_pad_numbers_are_jumpers no)
		(fp_poly
			(pts
				(xy -0.2794 -0.1016) (xy 0.2794 -0.1016) (xy 0.2794 0.9906) (xy -0.2794 0.9906)
			)
			(stroke
				(width 0)
				(type default)
			)
			(fill no)
			(layer "F.CrtYd")
		)
		(fp_line
			(start 0.2794 -0.1016)
			(end -0.2794 -0.1016)
			(stroke
				(width 0.1)
				(type default)
			)
			(layer "F.Fab")
		)
		(fp_line
			(start -0.2794 -0.1016)
			(end -0.2794 0.9906)
			(stroke
				(width 0.1)
				(type default)
			)
			(layer "F.Fab")
		)
		(fp_line
			(start 0.2794 0.9906)
			(end 0.2794 -0.1016)
			(stroke
				(width 0.1)
				(type default)
			)
			(layer "F.Fab")
		)
		(fp_line
			(start -0.2794 0.9906)
			(end 0.2794 0.9906)
			(stroke
				(width 0.1)
				(type default)
			)
			(layer "F.Fab")
		)
		(pad "1" smd rect
			(at 0 0 90)
			(size 0.508 0.508)
			(layers "F.Cu" "F.Mask" "F.Paste")
			(net "SPI_NIC_MOSI_R")
		)
		(pad "2" smd rect
			(at 0 0.889 90)
			(size 0.508 0.508)
			(layers "F.Cu" "F.Mask" "F.Paste")
			(net "SPI_NIC_MOSI")
		)
		(zone
			(layer "F.Cu")
			(hatch none 0.5)
			(connect_pads
				(clearance 0)
			)
			(min_thickness 0.25)
			(keepout
				(tracks allowed)
				(vias not_allowed)
				(pads allowed)
				(copperpour not_allowed)
				(footprints allowed)
			)
			(placement
				(enabled no)
				(sheetname "")
			)
			(fill
				(thermal_gap 0.5)
				(thermal_bridge_width 0.5)
				(island_removal_mode 0)
			)
			(polygon
				(pts
					(xy 490.5121 -45.7454) (xy 490.5121 -46.2534) (xy 490.8931 -46.2534) (xy 490.8931 -45.7454)
				)
			)
		)
		(zone
			(layer "F.Cu")
			(hatch none 0.5)
			(connect_pads
				(clearance 0)
			)
			(min_thickness 0.25)
			(keepout
				(tracks not_allowed)
				(vias allowed)
				(pads allowed)
				(copperpour not_allowed)
				(footprints allowed)
			)
			(placement
				(enabled no)
				(sheetname "")
			)
			(fill
				(thermal_gap 0.5)
				(thermal_bridge_width 0.5)
				(island_removal_mode 0)
			)
			(polygon
				(pts
					(xy 490.8931 -45.7454) (xy 490.8931 -46.2534) (xy 490.5121 -46.2534) (xy 490.5121 -45.7454)
				)
			)
		)
	)
	(footprint ""
		(layer "F.Cu")
		(at 155.575 -149.606 90)
		(property "Reference" "C3A4"
			(at 0 0 90)
			(layer "F.SilkS")
			(hide yes)
			(effects
				(font
					(size 1.27 1.27)
				)
			)
		)
		(property "Value" ""
			(at 0 0 90)
			(layer "F.Fab")
			(effects
				(font
					(size 1.27 1.27)
				)
			)
		)
		(duplicate_pad_numbers_are_jumpers no)
		(fp_rect
			(start -0.4953 1.6002)
			(end 0.4953 -0.2032)
			(stroke
				(width 0)
				(type default)
			)
			(fill no)
			(layer "F.CrtYd")
		)
		(fp_line
			(start 0.4953 -0.2032)
			(end 0.4953 1.6002)
			(stroke
				(width 0.1)
				(type default)
			)
			(layer "F.Fab")
		)
		(fp_line
			(start -0.4953 -0.2032)
			(end 0.4953 -0.2032)
			(stroke
				(width 0.1)
				(type default)
			)
			(layer "F.Fab")
		)
		(fp_line
			(start 0.4953 1.6002)
			(end -0.4953 1.6002)
			(stroke
				(width 0.1)
				(type default)
			)
			(layer "F.Fab")
		)
		(fp_line
			(start -0.4953 1.6002)
			(end -0.4953 -0.2032)
			(stroke
				(width 0.1)
				(type default)
			)
			(layer "F.Fab")
		)
		(pad "1" smd rect
			(at 0 0 90)
			(size 0.762 0.889)
			(layers "F.Cu" "F.Mask" "F.Paste")
			(net "PVPP_KLM")
		)
		(pad "2" smd rect
			(at 0 1.397 90)
			(size 0.762 0.889)
			(layers "F.Cu" "F.Mask" "F.Paste")
			(net "GND")
		)
		(zone
			(layer "F.Cu")
			(hatch none 0.5)
			(connect_pads
				(clearance 0)
			)
			(min_thickness 0.25)
			(keepout
				(tracks not_allowed)
				(vias allowed)
				(pads allowed)
				(copperpour not_allowed)
				(footprints allowed)
			)
			(placement
				(enabled no)
				(sheetname "")
			)
			(fill
				(thermal_gap 0.5)
				(thermal_bridge_width 0.5)
				(island_removal_mode 0)
			)
			(polygon
				(pts
					(xy 156.5275 -149.225) (xy 156.5275 -149.987) (xy 156.0195 -149.987) (xy 156.0195 -149.225)
				)
			)
		)
	)
	(footprint ""
		(layer "F.Cu")
		(at 415.29 -101.2698 90)
		(property "Reference" "R1W30"
			(at -0.8382 -0.67818 90)
			(unlocked yes)
			(layer "F.SilkS")
			(effects
				(font
					(size 0.4064 0.254)
					(thickness 0.1524)
				)
				(justify left)
			)
		)
		(property "Value" ""
			(at 0 0 90)
			(layer "F.Fab")
			(effects
				(font
					(size 1.27 1.27)
				)
			)
		)
		(duplicate_pad_numbers_are_jumpers no)
		(fp_poly
			(pts
				(xy -0.2794 -0.1016) (xy 0.2794 -0.1016) (xy 0.2794 0.9906) (xy -0.2794 0.9906)
			)
			(stroke
				(width 0)
				(type default)
			)
			(fill no)
			(layer "F.CrtYd")
		)
		(fp_line
			(start 0.2794 -0.1016)
			(end -0.2794 -0.1016)
			(stroke
				(width 0.1)
				(type default)
			)
			(layer "F.Fab")
		)
		(fp_line
			(start -0.2794 -0.1016)
			(end -0.2794 0.9906)
			(stroke
				(width 0.1)
				(type default)
			)
			(layer "F.Fab")
		)
		(fp_line
			(start 0.2794 0.9906)
			(end 0.2794 -0.1016)
			(stroke
				(width 0.1)
				(type default)
			)
			(layer "F.Fab")
		)
		(fp_line
			(start -0.2794 0.9906)
			(end 0.2794 0.9906)
			(stroke
				(width 0.1)
				(type default)
			)
			(layer "F.Fab")
		)
		(pad "1" smd rect
			(at 0 0 90)
			(size 0.508 0.508)
			(layers "F.Cu" "F.Mask" "F.Paste")
			(net "RST_BMC_SYSRST_BTN_OUT_B_N")
		)
		(pad "2" smd rect
			(at 0 0.889 90)
			(size 0.508 0.508)
			(layers "F.Cu" "F.Mask" "F.Paste")
			(net "RST_SYSTEM_BTN_BUF_N")
		)
		(zone
			(layer "F.Cu")
			(hatch none 0.5)
			(connect_pads
				(clearance 0)
			)
			(min_thickness 0.25)
			(keepout
				(tracks allowed)
				(vias not_allowed)
				(pads allowed)
				(copperpour not_allowed)
				(footprints allowed)
			)
			(placement
				(enabled no)
				(sheetname "")
			)
			(fill
				(thermal_gap 0.5)
				(thermal_bridge_width 0.5)
				(island_removal_mode 0)
			)
			(polygon
				(pts
					(xy 415.544 -101.0158) (xy 415.544 -101.5238) (xy 415.925 -101.5238) (xy 415.925 -101.0158)
				)
			)
		)
		(zone
			(layer "F.Cu")
			(hatch none 0.5)
			(connect_pads
				(clearance 0)
			)
			(min_thickness 0.25)
			(keepout
				(tracks not_allowed)
				(vias allowed)
				(pads allowed)
				(copperpour not_allowed)
				(footprints allowed)
			)
			(placement
				(enabled no)
				(sheetname "")
			)
			(fill
				(thermal_gap 0.5)
				(thermal_bridge_width 0.5)
				(island_removal_mode 0)
			)
			(polygon
				(pts
					(xy 415.925 -101.0158) (xy 415.925 -101.5238) (xy 415.544 -101.5238) (xy 415.544 -101.0158)
				)
			)
		)
	)
)
